(kicad_pcb
	(version 20260206)
	(generator "pcbnew")
	(generator_version "10.0")
	(general
		(thickness 1.6)
		(legacy_teardrops no)
	)
	(paper "A4")
	(title_block
		(title "Bryce Canyon_SCC_16316-1_OCP.brd")
		(comment 1 "Bryce Canyon / footprints 490-495 of 1561")
	)
	(layers
		(0 "F.Cu" signal "TOP")
		(4 "In1.Cu" signal "L2GND")
		(6 "In2.Cu" signal "L3")
		(8 "In3.Cu" signal "L4VCC")
		(10 "In4.Cu" signal "L5VCC")
		(12 "In5.Cu" signal "L6")
		(14 "In6.Cu" signal "L7GND")
		(2 "B.Cu" signal "BOTTOM")
		(9 "F.Adhes" user "F.Adhesive")
		(11 "B.Adhes" user "B.Adhesive")
		(13 "F.Paste" user "Package Geometry/Pastemask Top")
		(15 "B.Paste" user "Package Geometry/Pastemask Bottom")
		(5 "F.SilkS" user "Ref Des/Silkscreen Top")
		(7 "B.SilkS" user "Ref Des/Silkscreen Bottom")
		(1 "F.Mask" user "Board Geometry/Soldermask Top")
		(3 "B.Mask" user "Board Geometry/Soldermask Bottom")
		(17 "Dwgs.User" user "User.Drawings")
		(19 "Cmts.User" user "User.Comments")
		(21 "Eco1.User" user "User.Eco1")
		(23 "Eco2.User" user "User.Eco2")
		(25 "Edge.Cuts" user "Board Geometry/Outline")
		(27 "Margin" user)
		(31 "F.CrtYd" user "Package Geometry/Place Bound Top")
		(29 "B.CrtYd" user "Package Geometry/Place Bound Bottom")
		(35 "F.Fab" user "Ref Des/Assembly Top")
		(33 "B.Fab" user "Ref Des/Assembly Bottom")
	)
	(footprint ""
		(layer "F.Cu")
		(at 87.660734 -83.7565 180)
		(property "Reference" "R129"
			(at 0 0 180)
			(layer "F.SilkS")
			(hide yes)
			(effects
				(font
					(size 1.27 1.27)
				)
			)
		)
		(property "Value" "10KR2F-2-GP"
			(at 0.064008 -3.993896 180)
			(unlocked yes)
			(layer "F.Fab")
			(hide yes)
			(effects
				(font
					(size 1.016 1.016)
					(thickness 0.1524)
				)
			)
		)
		(property "Device Type" "R402H16"
			(at 0.064008 -5.517896 180)
			(unlocked yes)
			(layer "F.Fab")
			(hide yes)
			(effects
				(font
					(size 1.016 1.016)
					(thickness 0.1524)
				)
			)
		)
		(duplicate_pad_numbers_are_jumpers no)
		(fp_line
			(start 0.508 -0.9398)
			(end -0.508 -0.9398)
			(stroke
				(width 0.1524)
				(type default)
			)
			(layer "F.SilkS")
		)
		(fp_line
			(start -0.508 -0.9398)
			(end -0.508 0.9398)
			(stroke
				(width 0.1524)
				(type default)
			)
			(layer "F.SilkS")
		)
		(fp_rect
			(start -0.508 0.9398)
			(end 0.508 -0.9398)
			(stroke
				(width 0)
				(type default)
			)
			(fill no)
			(layer "F.CrtYd")
		)
		(fp_rect
			(start -0.508 0.9398)
			(end 0.508 -0.9398)
			(stroke
				(width 0)
				(type default)
			)
			(fill no)
			(layer "F.Fab")
		)
		(pad "1" smd custom
			(at 0 -0.4445 180)
			(size 0.1397 0.1397)
			(layers "F.Cu" "F.Mask" "F.Paste")
			(net "P3V3")
			(options
				(clearance outline)
				(anchor circle)
			)
			(primitives
				(gr_poly
					(pts
						(arc
							(start -0.1778 -0.2794)
							(mid -0.249642 -0.249642)
							(end -0.2794 -0.1778)
						)
						(arc
							(start -0.2794 0.1778)
							(mid -0.249642 0.249642)
							(end -0.1778 0.2794)
						)
						(arc
							(start 0.1778 0.2794)
							(mid 0.249642 0.249642)
							(end 0.2794 0.1778)
						)
						(arc
							(start 0.2794 -0.1778)
							(mid 0.249642 -0.249642)
							(end 0.1778 -0.2794)
						)
					)
					(width 0)
					(fill yes)
				)
			)
		)
		(pad "2" smd custom
			(at 0 0.4445 180)
			(size 0.1397 0.1397)
			(layers "F.Cu" "F.Mask" "F.Paste")
			(net "RESET_SENSE")
			(options
				(clearance outline)
				(anchor circle)
			)
			(primitives
				(gr_poly
					(pts
						(arc
							(start -0.1778 -0.2794)
							(mid -0.249642 -0.249642)
							(end -0.2794 -0.1778)
						)
						(arc
							(start -0.2794 0.1778)
							(mid -0.249642 0.249642)
							(end -0.1778 0.2794)
						)
						(arc
							(start 0.1778 0.2794)
							(mid 0.249642 0.249642)
							(end 0.2794 0.1778)
						)
						(arc
							(start 0.2794 -0.1778)
							(mid 0.249642 -0.249642)
							(end 0.1778 -0.2794)
						)
					)
					(width 0)
					(fill yes)
				)
			)
		)
	)
	(footprint ""
		(layer "F.Cu")
		(at 124.6632 -112.62868)
		(property "Reference" "TP21"
			(at 0 0 0)
			(layer "F.SilkS")
			(hide yes)
			(effects
				(font
					(size 1.27 1.27)
				)
			)
		)
		(property "Value" "TPAD28-2-GP"
			(at -0.0127 -1.6637 0)
			(unlocked yes)
			(layer "F.Fab")
			(hide yes)
			(effects
				(font
					(size 1.016 1.016)
					(thickness 0.1524)
				)
			)
		)
		(property "Device Type" "TPAD28"
			(at -0.0127 -3.1877 0)
			(unlocked yes)
			(layer "F.Fab")
			(hide yes)
			(effects
				(font
					(size 1.016 1.016)
					(thickness 0.1524)
				)
			)
		)
		(duplicate_pad_numbers_are_jumpers no)
		(fp_poly
			(pts
				(arc
					(start 0.3556 0)
					(mid -0.3556 0)
					(end 0.3556 0)
				)
			)
			(stroke
				(width 0)
				(type default)
			)
			(fill no)
			(layer "F.CrtYd")
		)
		(fp_poly
			(pts
				(arc
					(start 0.6096 0)
					(mid -0.6096 0)
					(end 0.6096 0)
				)
			)
			(stroke
				(width 0)
				(type default)
			)
			(fill no)
			(layer "F.Fab")
		)
		(pad "1" smd circle
			(at 0 0)
			(size 0.7112 0.7112)
			(layers "F.Cu" "F.Mask" "F.Paste")
			(net "INT_A1_CONN1")
		)
	)
	(footprint ""
		(layer "F.Cu")
		(at 181.8132 -97.6884 180)
		(property "Reference" "R285"
			(at 0 0 180)
			(layer "F.SilkS")
			(hide yes)
			(effects
				(font
					(size 1.27 1.27)
				)
			)
		)
		(property "Value" "D51R3F-2-GP"
			(at -0.0254 -2.5146 180)
			(unlocked yes)
			(layer "F.Fab")
			(hide yes)
			(effects
				(font
					(size 1.016 1.016)
					(thickness 0.1524)
				)
			)
		)
		(property "Device Type" "R603H22"
			(at -0.0254 -4.0386 180)
			(unlocked yes)
			(layer "F.Fab")
			(hide yes)
			(effects
				(font
					(size 1.016 1.016)
					(thickness 0.1524)
				)
			)
		)
		(duplicate_pad_numbers_are_jumpers no)
		(fp_line
			(start 0.2032 0)
			(end 0.4826 0)
			(stroke
				(width 0.2032)
				(type default)
			)
			(layer "F.SilkS")
		)
		(fp_line
			(start -0.4826 0)
			(end -0.2032 0)
			(stroke
				(width 0.2032)
				(type default)
			)
			(layer "F.SilkS")
		)
		(fp_rect
			(start -0.5842 1.3335)
			(end 0.5842 -1.3335)
			(stroke
				(width 0)
				(type default)
			)
			(fill no)
			(layer "F.CrtYd")
		)
		(fp_rect
			(start -0.5842 1.3335)
			(end 0.5842 -1.3335)
			(stroke
				(width 0)
				(type default)
			)
			(fill no)
			(layer "F.Fab")
		)
		(pad "1" smd custom
			(at 0 -0.762 180)
			(size 0.2159 0.2159)
			(layers "F.Cu" "F.Mask" "F.Paste")
			(net "P0V975")
			(options
				(clearance outline)
				(anchor circle)
			)
			(primitives
				(gr_poly
					(pts
						(arc
							(start -0.3302 -0.4318)
							(mid -0.402042 -0.402042)
							(end -0.4318 -0.3302)
						)
						(arc
							(start -0.4318 0.3302)
							(mid -0.402042 0.402042)
							(end -0.3302 0.4318)
						)
						(arc
							(start 0.3302 0.4318)
							(mid 0.402042 0.402042)
							(end 0.4318 0.3302)
						)
						(arc
							(start 0.4318 -0.3302)
							(mid 0.402042 -0.402042)
							(end 0.3302 -0.4318)
						)
					)
					(width 0)
					(fill yes)
				)
			)
		)
		(pad "2" smd custom
			(at 0 0.762 180)
			(size 0.2159 0.2159)
			(layers "F.Cu" "F.Mask" "F.Paste")
			(net "SAS0_AVDD")
			(options
				(clearance outline)
				(anchor circle)
			)
			(primitives
				(gr_poly
					(pts
						(arc
							(start -0.3302 -0.4318)
							(mid -0.402042 -0.402042)
							(end -0.4318 -0.3302)
						)
						(arc
							(start -0.4318 0.3302)
							(mid -0.402042 0.402042)
							(end -0.3302 0.4318)
						)
						(arc
							(start 0.3302 0.4318)
							(mid 0.402042 0.402042)
							(end 0.4318 0.3302)
						)
						(arc
							(start 0.4318 -0.3302)
							(mid 0.402042 -0.402042)
							(end 0.3302 -0.4318)
						)
					)
					(width 0)
					(fill yes)
				)
			)
		)
	)
	(footprint ""
		(layer "F.Cu")
		(at 173.7614 -112.0013 90)
		(property "Reference" "R93"
			(at 0 0 90)
			(layer "F.SilkS")
			(hide yes)
			(effects
				(font
					(size 1.27 1.27)
				)
			)
		)
		(property "Value" "4K75R2F-1-GP"
			(at 0.064008 -3.993896 90)
			(unlocked yes)
			(layer "F.Fab")
			(hide yes)
			(effects
				(font
					(size 1.016 1.016)
					(thickness 0.1524)
				)
			)
		)
		(property "Device Type" "R402H16"
			(at 0.064008 -5.517896 90)
			(unlocked yes)
			(layer "F.Fab")
			(hide yes)
			(effects
				(font
					(size 1.016 1.016)
					(thickness 0.1524)
				)
			)
		)
		(duplicate_pad_numbers_are_jumpers no)
		(fp_line
			(start 0.508 -0.9398)
			(end -0.508 -0.9398)
			(stroke
				(width 0.1524)
				(type default)
			)
			(layer "F.SilkS")
		)
		(fp_line
			(start -0.508 -0.9398)
			(end -0.508 0.9398)
			(stroke
				(width 0.1524)
				(type default)
			)
			(layer "F.SilkS")
		)
		(fp_rect
			(start -0.508 0.9398)
			(end 0.508 -0.9398)
			(stroke
				(width 0)
				(type default)
			)
			(fill no)
			(layer "F.CrtYd")
		)
		(fp_rect
			(start -0.508 0.9398)
			(end 0.508 -0.9398)
			(stroke
				(width 0)
				(type default)
			)
			(fill no)
			(layer "F.Fab")
		)
		(pad "1" smd custom
			(at 0 -0.4445 90)
			(size 0.1397 0.1397)
			(layers "F.Cu" "F.Mask" "F.Paste")
			(net "P3V3")
			(options
				(clearance outline)
				(anchor circle)
			)
			(primitives
				(gr_poly
					(pts
						(arc
							(start -0.1778 -0.2794)
							(mid -0.249642 -0.249642)
							(end -0.2794 -0.1778)
						)
						(arc
							(start -0.2794 0.1778)
							(mid -0.249642 0.249642)
							(end -0.1778 0.2794)
						)
						(arc
							(start 0.1778 0.2794)
							(mid 0.249642 0.249642)
							(end 0.2794 0.1778)
						)
						(arc
							(start 0.2794 -0.1778)
							(mid 0.249642 -0.249642)
							(end 0.1778 -0.2794)
						)
					)
					(width 0)
					(fill yes)
				)
			)
		)
		(pad "2" smd custom
			(at 0 0.4445 90)
			(size 0.1397 0.1397)
			(layers "F.Cu" "F.Mask" "F.Paste")
			(net "P1V8_E_EN")
			(options
				(clearance outline)
				(anchor circle)
			)
			(primitives
				(gr_poly
					(pts
						(arc
							(start -0.1778 -0.2794)
							(mid -0.249642 -0.249642)
							(end -0.2794 -0.1778)
						)
						(arc
							(start -0.2794 0.1778)
							(mid -0.249642 0.249642)
							(end -0.1778 0.2794)
						)
						(arc
							(start 0.1778 0.2794)
							(mid 0.249642 0.249642)
							(end 0.2794 0.1778)
						)
						(arc
							(start 0.2794 -0.1778)
							(mid 0.249642 -0.249642)
							(end 0.1778 -0.2794)
						)
					)
					(width 0)
					(fill yes)
				)
			)
		)
	)
	(footprint ""
		(layer "F.Cu")
		(at 139.310618 -64.972184)
		(property "Reference" "VIA16"
			(at 0 0 0)
			(layer "F.SilkS")
			(hide yes)
			(effects
				(font
					(size 1.27 1.27)
				)
			)
		)
		(property "Value" "100OHM-8L-1D6MM-L13-GP"
			(at 3.2893 0.0508 0)
			(unlocked yes)
			(layer "F.Fab")
			(hide yes)
			(effects
				(font
					(size 1.016 1.016)
					(thickness 0.1524)
				)
			)
		)
		(property "Device Type" "VIA-PCIE-4P-409091"
			(at 3.2893 -1.4732 0)
			(unlocked yes)
			(layer "F.Fab")
			(hide yes)
			(effects
				(font
					(size 1.016 1.016)
					(thickness 0.1524)
				)
			)
		)
		(duplicate_pad_numbers_are_jumpers no)
		(fp_rect
			(start -2.0447 0.4572)
			(end 2.0447 -0.4572)
			(stroke
				(width 0)
				(type default)
			)
			(fill no)
			(layer "F.CrtYd")
		)
		(fp_rect
			(start -2.0447 0.4572)
			(end 2.0447 -0.4572)
			(stroke
				(width 0)
				(type default)
			)
			(fill no)
			(layer "F.Fab")
		)
		(pad "1" thru_hole circle
			(at -1.5875 0)
			(size 0.508 0.508)
			(drill 0.254)
			(layers "*.Cu" "*.Mask")
			(remove_unused_layers no)
			(net "GND")
			(clearance 0.2032)
			(thermal_gap 0.2032)
		)
		(pad "2" thru_hole circle
			(at -0.5715 0)
			(size 0.508 0.508)
			(drill 0.254)
			(layers "*.Cu" "*.Mask")
			(remove_unused_layers no)
			(net "PHY_IOC_TO_SCC_C_47_DP")
			(clearance 0.2032)
			(thermal_gap 0.2032)
		)
		(pad "3" thru_hole circle
			(at 0.5715 0)
			(size 0.508 0.508)
			(drill 0.254)
			(layers "*.Cu" "*.Mask")
			(remove_unused_layers no)
			(net "PHY_IOC_TO_SCC_C_47_DN")
			(clearance 0.2032)
			(thermal_gap 0.2032)
		)
		(pad "4" thru_hole circle
			(at 1.5875 0)
			(size 0.508 0.508)
			(drill 0.254)
			(layers "*.Cu" "*.Mask")
			(remove_unused_layers no)
			(net "GND")
			(clearance 0.2032)
			(thermal_gap 0.2032)
		)
	)
	(footprint ""
		(layer "F.Cu")
		(at 41.86174 -36.939474 180)
		(property "Reference" "C604"
			(at 0 0 180)
			(layer "F.SilkS")
			(hide yes)
			(effects
				(font
					(size 1.27 1.27)
				)
			)
		)
		(property "Value" "SCD1U16V2KX-3GP"
			(at 1.1811 -2.7051 180)
			(unlocked yes)
			(layer "F.Fab")
			(hide yes)
			(effects
				(font
					(size 1.016 1.016)
					(thickness 0.1524)
				)
			)
		)
		(property "Device Type" "C402H22"
			(at 1.1811 -4.2291 180)
			(unlocked yes)
			(layer "F.Fab")
			(hide yes)
			(effects
				(font
					(size 1.016 1.016)
					(thickness 0.1524)
				)
			)
		)
		(duplicate_pad_numbers_are_jumpers no)
		(fp_rect
			(start -0.4318 0.9525)
			(end 0.4318 -0.9525)
			(stroke
				(width 0)
				(type default)
			)
			(fill no)
			(layer "F.CrtYd")
		)
		(fp_rect
			(start -0.4318 0.9525)
			(end 0.4318 -0.9525)
			(stroke
				(width 0)
				(type default)
			)
			(fill no)
			(layer "F.Fab")
		)
		(pad "1" smd custom
			(at 0 -0.4445 180)
			(size 0.1524 0.1524)
			(layers "F.Cu" "F.Mask" "F.Paste")
			(net "P0V9_BST")
			(options
				(clearance outline)
				(anchor circle)
			)
			(primitives
				(gr_poly
					(pts
						(arc
							(start 0.3048 -0.2032)
							(mid 0.275042 -0.275042)
							(end 0.2032 -0.3048)
						)
						(arc
							(start -0.2032 -0.3048)
							(mid -0.275042 -0.275042)
							(end -0.3048 -0.2032)
						)
						(arc
							(start -0.3048 0.2032)
							(mid -0.275042 0.275042)
							(end -0.2032 0.3048)
						)
						(arc
							(start 0.2032 0.3048)
							(mid 0.275042 0.275042)
							(end 0.3048 0.2032)
						)
					)
					(width 0)
					(fill yes)
				)
			)
		)
		(pad "2" smd custom
			(at 0 0.4445 180)
			(size 0.1524 0.1524)
			(layers "F.Cu" "F.Mask" "F.Paste")
			(net "P0V9_BST_R")
			(options
				(clearance outline)
				(anchor circle)
			)
			(primitives
				(gr_poly
					(pts
						(arc
							(start 0.3048 -0.2032)
							(mid 0.275042 -0.275042)
							(end 0.2032 -0.3048)
						)
						(arc
							(start -0.2032 -0.3048)
							(mid -0.275042 -0.275042)
							(end -0.3048 -0.2032)
						)
						(arc
							(start -0.3048 0.2032)
							(mid -0.275042 0.275042)
							(end -0.2032 0.3048)
						)
						(arc
							(start 0.2032 0.3048)
							(mid 0.275042 0.275042)
							(end 0.3048 0.2032)
						)
					)
					(width 0)
					(fill yes)
				)
			)
		)
	)
)
